#ISCELL
  pure_quanta quanta_title_block_c *
  *
#CELL
  pure_quanta pt5161lrs *
  page459_i1
#ISCELL
  standard tap *
  page459_i10
#ISCELL
  standard tap *
  page459_i11
#ISCELL
  standard tap *
  page459_i12
#ISCELL
  standard tap *
  page459_i13
#ISCELL
  standard tap *
  page459_i14
#ISCELL
  standard tap *
  page459_i15
#ISCELL
  standard tap *
  page459_i16
#ISCELL
  standard tap *
  page459_i17
#ISCELL
  standard offpage *
  page459_i18
#ISCELL
  standard offpage *
  page459_i19
#ISCELL
  standard tap *
  page459_i2
#ISCELL
  standard tap *
  page459_i20
#ISCELL
  standard tap *
  page459_i21
#ISCELL
  standard tap *
  page459_i22
#ISCELL
  standard tap *
  page459_i23
#ISCELL
  standard tap *
  page459_i24
#ISCELL
  standard tap *
  page459_i25
#ISCELL
  standard tap *
  page459_i26
#ISCELL
  standard tap *
  page459_i27
#ISCELL
  standard tap *
  page459_i28
#ISCELL
  standard tap *
  page459_i29
#ISCELL
  standard tap *
  page459_i3
#ISCELL
  standard tap *
  page459_i30
#ISCELL
  standard tap *
  page459_i31
#ISCELL
  standard tap *
  page459_i32
#ISCELL
  standard tap *
  page459_i33
#ISCELL
  standard tap *
  page459_i34
#ISCELL
  standard offpage *
  page459_i35
#ISCELL
  standard offpage *
  page459_i36
#ISCELL
  standard tap *
  page459_i37
#CELL
  pure_quanta pt5161lrs *
  page459_i38
#ISCELL
  standard tap *
  page459_i4
#ISCELL
  standard tap *
  page459_i5
#ISCELL
  standard tap *
  page459_i6
#ISCELL
  standard tap *
  page459_i7
#ISCELL
  standard tap *
  page459_i8
#ISCELL
  standard tap *
  page459_i9
